#ISCELL
  pure_quanta quanta_title_block_c *
  *
#ISCELL
  pure_quanta_power cad_note *
  *
#ISCELL
  pure_quanta_power universal_power *
  page84_i1
#ISCELL
  standard offpage *
  page84_i10
#ISCELL
  standard offpage *
  page84_i11
#ISCELL
  standard offpage *
  page84_i12
#ISCELL
  standard offpage *
  page84_i13
#ISCELL
  pure_quanta_power universal_gnd *
  page84_i2
#ISCELL
  standard offpage *
  page84_i23
#ISCELL
  mstr_standard offpage *
  page84_i24
#ISCELL
  standard offpage *
  page84_i25
#ISCELL
  standard offpage *
  page84_i26
#ISCELL
  standard offpage *
  page84_i27
#ISCELL
  standard offpage *
  page84_i28
#CELL
  pure_quanta q_res *
  page84_i29
#CELL
  pure_quanta q_cap *
  page84_i3
#ISCELL
  standard offpage *
  page84_i30
#ISCELL
  standard offpage *
  page84_i31
#CELL
  pure_quanta q_res *
  page84_i32
#CELL
  pure_quanta q_res *
  page84_i33
#CELL
  pure_quanta q_res *
  page84_i34
#CELL
  pure_quanta q_res *
  page84_i35
#CELL
  pure_quanta q_res *
  page84_i36
#ISCELL
  standard offpage *
  page84_i37
#ISCELL
  standard offpage *
  page84_i38
#ISCELL
  standard offpage *
  page84_i39
#CELL
  pure_quanta conn8_hbb1081l200d8h *
  page84_i4
#ISCELL
  standard offpage *
  page84_i40
#ISCELL
  standard offpage *
  page84_i41
#ISCELL
  pure_quanta_power vcc_core *
  page84_i42
#CELL
  pure_quanta q_res *
  page84_i43
#CELL
  pure_quanta q_res *
  page84_i44
#CELL
  pure_quanta q_res *
  page84_i45
#CELL
  pure_quanta q_res *
  page84_i46
#CELL
  pure_quanta q_res *
  page84_i47
#ISCELL
  standard offpage *
  page84_i48
#ISCELL
  standard offpage *
  page84_i49
#ISCELL
  pure_quanta_power universal_gnd *
  page84_i5
#ISCELL
  pure_quanta_power universal_gnd *
  page84_i50
#CELL
  pure_quanta q_led *
  page84_i51
#CELL
  pure_quanta mosfet_dual_6p *
  page84_i52
#ISCELL
  pure_quanta_power universal_gnd *
  page84_i53
#CELL
  pure_quanta q_led *
  page84_i54
#CELL
  pure_quanta q_res *
  page84_i55
#ISCELL
  standard offpage *
  page84_i56
#CELL
  pure_quanta q_res *
  page84_i57
#ISCELL
  pure_quanta_power universal_power *
  page84_i58
#ISCELL
  standard offpage *
  page84_i59
#CELL
  pure_quanta q_res *
  page84_i6
#ISCELL
  standard offpage *
  page84_i60
#ISCELL
  standard offpage *
  page84_i61
#CELL
  pure_quanta q_res *
  page84_i62
#CELL
  pure_quanta q_res *
  page84_i63
#CELL
  pure_quanta q_res *
  page84_i64
#CELL
  pure_quanta q_res *
  page84_i7
#CELL
  pure_quanta q_res *
  page84_i8
#CELL
  pure_quanta q_res *
  page84_i9
